FILE_TYPE = CONNECTIVITY;
{Allegro Design Entry HDL 16.6-p007 (v16-6-112F) 10/10/2012}
"PAGE_NUMBER" = 78;
0"NC";
1"M_G_DQS_DN<17:0>";
2"M_G_DQS_DP<17:0>";
3"M_G_DQ<63:0>";
4"M_G_MA<17:0>";
5"M_G_BA<1:0>";
6"M_G_BG<1:0>";
7"M_G_CLK_DN<3:0>";
8"M_G_CS_N<7:0>";
9"M_G_CLK_DP<3:0>";
10"M_G_CKE<3:0>";
11"M_G_ODT<3:0>";
12"M_G_ECC<7:0>";
13"GND\g";
14"PVPP_GHJ\g";
15"GND\g";
16"GND\g";
17"P12V_NVDIMM_GHJ\g";
18"GND\g";
19"PVPP_GHJ\g";
20"PVDDQ_GHJ\g";
21"PVTT_GHJ\g";
22"M_G_VREF";
23"M_G_ACT_N";
24"M_G_ALERT_N";
25"TP_CH_G_DIMM0_RFU_2";
26"TP_CH_G_DIMM0_RFU_0";
27"TP_CH_G_DIMM0_RFU_1";
28"FM_ADR_COMPLETE_GHJ_N";
29"FM_DIMM_EVENT_COD_N";
30"SMB_DDR_GHJ_VPP_SDA";
31"SMB_DDR_GHJ_VPP_SCL";
32"M_G_ECC<4>";
33"M_G_ECC<3>";
34"M_G_ECC<2>";
35"M_G_ECC<1>";
36"M_G_ECC<0>";
37"M_G_PAR";
38"M_GHJ_RST_N";
39"M_G_ECC<6>";
40"M_G_ECC<5>";
41"M_G_ECC<7>";
42"M_G_ODT<2>";
43"M_G_ODT<3>";
44"M_G_CKE<3>";
45"M_G_CKE<2>";
46"M_G_CLK_DN<3>";
47"M_G_CLK_DP<2>";
48"M_G_CS_N<7>";
49"M_G_CLK_DP<3>";
50"M_G_CS_N<6>";
51"M_G_CS_N<5>";
52"M_G_CS_N<4>";
53"M_G_CLK_DN<2>";
54"M_G_C<2>";
55"M_G_BA<1>";
56"M_G_MA<0>";
57"M_G_MA<1>";
58"M_G_MA<3>";
59"M_G_MA<4>";
60"M_G_BG<0>";
61"M_G_BG<1>";
62"M_G_BA<0>";
63"M_G_MA<2>";
64"M_G_MA<12>";
65"M_G_MA<13>";
66"M_G_MA<5>";
67"M_G_MA<6>";
68"M_G_MA<7>";
69"M_G_MA<8>";
70"M_G_MA<9>";
71"M_G_MA<10>";
72"M_G_MA<11>";
73"M_G_MA<14>";
74"M_G_MA<17>";
75"M_G_MA<15>";
76"M_G_MA<16>";
77"M_G_DQ<63>";
78"M_G_DQ<29>";
79"M_G_DQ<28>";
80"M_G_DQ<62>";
81"M_G_DQ<61>";
82"M_G_DQ<60>";
83"M_G_DQ<59>";
84"M_G_DQ<56>";
85"M_G_DQ<55>";
86"M_G_DQ<46>";
87"M_G_DQ<45>";
88"M_G_DQ<44>";
89"M_G_DQ<43>";
90"M_G_DQ<42>";
91"M_G_DQ<41>";
92"M_G_DQ<40>";
93"M_G_DQ<39>";
94"M_G_DQ<37>";
95"M_G_DQ<34>";
96"M_G_DQ<33>";
97"M_G_DQ<32>";
98"M_G_DQ<31>";
99"M_G_DQ<30>";
100"M_G_DQ<25>";
101"M_G_DQ<24>";
102"M_G_DQ<23>";
103"M_G_DQ<22>";
104"M_G_DQ<21>";
105"M_G_DQ<20>";
106"M_G_DQ<19>";
107"M_G_DQ<18>";
108"M_G_DQ<16>";
109"M_G_DQ<14>";
110"M_G_DQ<13>";
111"M_G_DQ<12>";
112"M_G_DQ<11>";
113"M_G_DQ<9>";
114"M_G_DQ<7>";
115"M_G_DQ<6>";
116"M_G_DQ<1>";
117"M_G_DQ<0>";
118"M_G_DQ<35>";
119"M_G_DQ<36>";
120"M_G_DQ<38>";
121"M_G_DQ<26>";
122"M_G_DQ<15>";
123"M_G_DQ<17>";
124"M_G_DQ<57>";
125"M_G_DQ<58>";
126"M_G_DQ<54>";
127"M_G_DQ<53>";
128"M_G_DQ<52>";
129"M_G_DQ<51>";
130"M_G_DQ<50>";
131"M_G_DQ<49>";
132"M_G_DQ<48>";
133"M_G_DQ<47>";
134"M_G_DQ<2>";
135"M_G_DQ<3>";
136"M_G_DQ<4>";
137"M_G_DQ<5>";
138"M_G_DQ<10>";
139"M_G_DQ<8>";
140"M_G_DQ<27>";
141"M_G_DQS_DP<0>";
142"M_G_DQS_DP<1>";
143"M_G_DQS_DP<2>";
144"M_G_DQS_DP<3>";
145"M_G_DQS_DP<4>";
146"M_G_DQS_DP<5>";
147"M_G_DQS_DP<6>";
148"M_G_DQS_DP<7>";
149"M_G_DQS_DP<8>";
150"M_G_DQS_DP<9>";
151"M_G_DQS_DN<0>";
152"M_G_DQS_DN<1>";
153"M_G_DQS_DN<2>";
154"M_G_DQS_DN<3>";
155"M_G_DQS_DN<4>";
156"M_G_DQS_DN<5>";
157"M_G_DQS_DN<6>";
158"M_G_DQS_DN<7>";
159"M_G_DQS_DN<8>";
160"M_G_DQS_DN<9>";
161"M_G_DQS_DP<10>";
162"M_G_DQS_DP<11>";
163"M_G_DQS_DP<12>";
164"M_G_DQS_DP<13>";
165"M_G_DQS_DP<14>";
166"M_G_DQS_DP<15>";
167"M_G_DQS_DP<16>";
168"M_G_DQS_DP<17>";
169"M_G_DQS_DN<10>";
170"M_G_DQS_DN<11>";
171"M_G_DQS_DN<12>";
172"M_G_DQS_DN<13>";
173"M_G_DQS_DN<14>";
174"M_G_DQS_DN<15>";
175"M_G_DQS_DN<16>";
176"M_G_DQS_DN<17>";
%"GND"
"1","(-2675,625)","0","mstr_symbols","I1";
;
HDL_POWER"GND"
ROOM"DDR4_GH_G"
BODY_TYPE"PLUMBING"
BOM_COST"MEM"
CDS_LIB"mstr_symbols"
SIZE"1B"
VOLTAGE"0.0V";
"A\NAC"13;
%"TAP"
"6","(125,2925)","2","mstr_standard","I100";
;
HDL_TAP"TRUE"
BODY_TYPE"PLUMBING"
CDS_LIB"mstr_standard";
"B \NAC \NWC"3;
"S \NAC"
BN"37"94;
%"TAP"
"6","(125,3125)","2","mstr_standard","I101";
;
HDL_TAP"TRUE"
BODY_TYPE"PLUMBING"
CDS_LIB"mstr_standard";
"B \NAC \NWC"3;
"S \NAC"
BN"41"91;
%"TAP"
"6","(125,3025)","2","mstr_standard","I102";
;
HDL_TAP"TRUE"
BODY_TYPE"PLUMBING"
CDS_LIB"mstr_standard";
"B \NAC \NWC"3;
"S \NAC"
BN"39"93;
%"TAP"
"6","(125,3075)","2","mstr_standard","I103";
;
HDL_TAP"TRUE"
BODY_TYPE"PLUMBING"
CDS_LIB"mstr_standard";
"B \NAC \NWC"3;
"S \NAC"
BN"40"92;
%"TAP"
"6","(125,3175)","2","mstr_standard","I104";
;
HDL_TAP"TRUE"
BODY_TYPE"PLUMBING"
CDS_LIB"mstr_standard";
"B \NAC \NWC"3;
"S \NAC"
BN"42"90;
%"TAP"
"6","(125,3225)","2","mstr_standard","I105";
;
HDL_TAP"TRUE"
BODY_TYPE"PLUMBING"
CDS_LIB"mstr_standard";
"B \NAC \NWC"3;
"S \NAC"
BN"43"89;
%"TAP"
"6","(125,3275)","2","mstr_standard","I106";
;
HDL_TAP"TRUE"
BODY_TYPE"PLUMBING"
CDS_LIB"mstr_standard";
"B \NAC \NWC"3;
"S \NAC"
BN"44"88;
%"TAP"
"6","(125,3325)","2","mstr_standard","I107";
;
HDL_TAP"TRUE"
BODY_TYPE"PLUMBING"
CDS_LIB"mstr_standard";
"B \NAC \NWC"3;
"S \NAC"
BN"45"87;
%"TAP"
"6","(125,3375)","2","mstr_standard","I108";
;
HDL_TAP"TRUE"
BODY_TYPE"PLUMBING"
CDS_LIB"mstr_standard";
"B \NAC \NWC"3;
"S \NAC"
BN"46"86;
%"TAP"
"6","(125,3475)","2","mstr_standard","I109";
;
HDL_TAP"TRUE"
BODY_TYPE"PLUMBING"
CDS_LIB"mstr_standard";
"B \NAC \NWC"3;
"S \NAC"
BN"48"132;
%"TAP"
"6","(125,3425)","2","mstr_standard","I110";
;
HDL_TAP"TRUE"
BODY_TYPE"PLUMBING"
CDS_LIB"mstr_standard";
"B \NAC \NWC"3;
"S \NAC"
BN"47"133;
%"TAP"
"6","(125,3525)","2","mstr_standard","I111";
;
HDL_TAP"TRUE"
BODY_TYPE"PLUMBING"
CDS_LIB"mstr_standard";
"B \NAC \NWC"3;
"S \NAC"
BN"49"131;
%"TAP"
"6","(125,3575)","2","mstr_standard","I112";
;
HDL_TAP"TRUE"
BODY_TYPE"PLUMBING"
CDS_LIB"mstr_standard";
"B \NAC \NWC"3;
"S \NAC"
BN"50"130;
%"TAP"
"6","(125,3625)","2","mstr_standard","I113";
;
HDL_TAP"TRUE"
BODY_TYPE"PLUMBING"
CDS_LIB"mstr_standard";
"B \NAC \NWC"3;
"S \NAC"
BN"51"129;
%"TAP"
"6","(125,3775)","2","mstr_standard","I114";
;
HDL_TAP"TRUE"
BODY_TYPE"PLUMBING"
CDS_LIB"mstr_standard";
"B \NAC \NWC"3;
"S \NAC"
BN"54"126;
%"TAP"
"6","(125,3725)","2","mstr_standard","I115";
;
HDL_TAP"TRUE"
BODY_TYPE"PLUMBING"
CDS_LIB"mstr_standard";
"B \NAC \NWC"3;
"S \NAC"
BN"53"127;
%"TAP"
"6","(125,3675)","2","mstr_standard","I116";
;
HDL_TAP"TRUE"
BODY_TYPE"PLUMBING"
CDS_LIB"mstr_standard";
"B \NAC \NWC"3;
"S \NAC"
BN"52"128;
%"TAP"
"6","(125,3825)","2","mstr_standard","I117";
;
HDL_TAP"TRUE"
BODY_TYPE"PLUMBING"
CDS_LIB"mstr_standard";
"B \NAC \NWC"3;
"S \NAC"
BN"55"85;
%"TAP"
"6","(125,3875)","2","mstr_standard","I118";
;
HDL_TAP"TRUE"
BODY_TYPE"PLUMBING"
CDS_LIB"mstr_standard";
"B \NAC \NWC"3;
"S \NAC"
BN"56"84;
%"PVPP_GHJ"
"1","(750,2750)","0","mstr_symbols","I119";
;
HDL_POWER"PVPP_GHJ"
ROOM"DDR4_GH_G"
BODY_TYPE"PLUMBING"
CDS_LIB"mstr_symbols"
BOM_COST"MEM"
VOLTAGE"2.5V";
"G\NAC"14;
%"TAP"
"6","(-1375,1825)","0","mstr_standard","I12";
;
HDL_TAP"TRUE"
BODY_TYPE"PLUMBING"
CDS_LIB"mstr_standard";
"B \NAC \NWC"12;
"S \NAC"
BN"0"36;
%"SCONN288_H44441003"
"2","(1750,4000)","0","mstr_sconn","I120";
;
CDS_SEC"2"
ROOM"DDR4_GH_G"
CDS_LOCATION"J9T1"
SEC"2"
SEC_TYPE"PIP"
CDS_LIB"mstr_sconn"
BOM_COST"MEM"
PACK_TYPE"PIP"
MATERIAL"SCONN"
PART_NUMBER"H44441-003"
LOCATION"J9T1";
"DQS0N"
$PN"152"151;
"DQS0P"
$PN"153"141;
"DQS10N"
$PN"19"169;
"DQS10P"
$PN"18"161;
"DQS11N"
$PN"30"170;
"DQS11P"
$PN"29"162;
"DQS12N"
$PN"41"171;
"DQS12P"
$PN"40"163;
"DQS13N"
$PN"100"172;
"DQS13P"
$PN"99"164;
"DQS14N"
$PN"111"173;
"DQS14P"
$PN"110"165;
"DQS15N"
$PN"122"174;
"DQS15P"
$PN"121"166;
"DQS16N"
$PN"133"175;
"DQS16P"
$PN"132"167;
"DQS17N"
$PN"52"176;
"DQS17P"
$PN"51"168;
"DQS1N"
$PN"163"152;
"DQS1P"
$PN"164"142;
"DQS2N"
$PN"174"153;
"DQS2P"
$PN"175"143;
"DQS3N"
$PN"185"154;
"DQS3P"
$PN"186"144;
"DQS4N"
$PN"244"155;
"DQS4P"
$PN"245"145;
"DQS5N"
$PN"255"156;
"DQS5P"
$PN"256"146;
"DQS6N"
$PN"266"157;
"DQS6P"
$PN"267"147;
"DQS7N"
$PN"277"158;
"DQS7P"
$PN"278"148;
"DQS8N"
$PN"196"159;
"DQS8P"
$PN"197"149;
"DQS9N"
$PN"8"160;
"DQS9P"
$PN"7"150;
%"TAP"
"6","(-1375,3925)","0","mstr_standard","I122";
;
HDL_TAP"TRUE"
BODY_TYPE"PLUMBING"
CDS_LIB"mstr_standard";
"B \NAC \NWC"4;
"S \NAC"
BN"11"72;
%"TAP"
"6","(-1375,3975)","0","mstr_standard","I123";
;
HDL_TAP"TRUE"
BODY_TYPE"PLUMBING"
CDS_LIB"mstr_standard";
"B \NAC \NWC"4;
"S \NAC"
BN"12"64;
%"TAP"
"6","(-1375,4125)","0","mstr_standard","I124";
;
HDL_TAP"TRUE"
BODY_TYPE"PLUMBING"
CDS_LIB"mstr_standard";
"B \NAC \NWC"4;
"S \NAC"
BN"15"75;
%"TAP"
"6","(-1375,4075)","0","mstr_standard","I125";
;
HDL_TAP"TRUE"
BODY_TYPE"PLUMBING"
CDS_LIB"mstr_standard";
"B \NAC \NWC"4;
"S \NAC"
BN"14"73;
%"TAP"
"6","(-1375,4025)","0","mstr_standard","I126";
;
HDL_TAP"TRUE"
BODY_TYPE"PLUMBING"
CDS_LIB"mstr_standard";
"B \NAC \NWC"4;
"S \NAC"
BN"13"65;
%"TAP"
"6","(-1375,4225)","0","mstr_standard","I127";
;
HDL_TAP"TRUE"
BODY_TYPE"PLUMBING"
CDS_LIB"mstr_standard";
"B \NAC \NWC"4;
"S \NAC"
BN"17"74;
%"TAP"
"6","(-1375,4175)","0","mstr_standard","I128";
;
HDL_TAP"TRUE"
BODY_TYPE"PLUMBING"
CDS_LIB"mstr_standard";
"B \NAC \NWC"4;
"S \NAC"
BN"16"76;
%"SCONN288_H44441003"
"1","(-625,2575)","0","mstr_sconn","I13";
;
CDS_SEC"1"
ROOM"DDR4_GH_G"
CDS_LOCATION"J9T1"
SEC"1"
SEC_TYPE"PIP"
CDS_LIB"mstr_sconn"
BOM_COST"MEM"
PACK_TYPE"PIP"
MATERIAL"SCONN"
PART_NUMBER"H44441-003"
LOCATION"J9T1";
"DQ<63>"
$PN"280"77;
"BA<1>"
$PN"224"55;
"CK1N"
$PN"219"46;
"CK0P"
$PN"74"47;
"S3_N_C<1>"
$PN"237"48;
"S2_N_C<0>"
$PN"93"50;
"S1_N"
$PN"89"51;
"DQ<29>"
$PN"181"78;
"DQ<28>"
$PN"36"79;
"C<2>"
$PN"235"54;
"A0"
$PN"79"56;
"A1"
$PN"72"57;
"A12"
$PN"65"64;
"A13"
$PN"232"65;
"A17"
$PN"234"74;
"A3"
$PN"71"58;
"A4"
$PN"214"59;
"A5"
$PN"213"66;
"A6"
$PN"69"67;
"A7"
$PN"211"68;
"A8"
$PN"68"69;
"A9"
$PN"66"70;
"CB<6>"
$PN"54"39;
"CB<5>"
$PN"192"40;
"CB<4>"
$PN"47"32;
"CB<3>"
$PN"201"33;
"CB<2>"
$PN"56"34;
"CB<1>"
$PN"194"35;
"CB<0>"
$PN"49"36;
"CK0N"
$PN"75"53;
"CKE<1>"
$PN"203"44;
"DQ<62>"
$PN"135"80;
"DQ<61>"
$PN"273"81;
"DQ<60>"
$PN"128"82;
"DQ<59>"
$PN"282"83;
"DQ<56>"
$PN"130"84;
"DQ<55>"
$PN"269"85;
"DQ<46>"
$PN"113"86;
"DQ<45>"
$PN"251"87;
"DQ<44>"
$PN"106"88;
"DQ<43>"
$PN"260"89;
"DQ<42>"
$PN"115"90;
"DQ<41>"
$PN"253"91;
"DQ<40>"
$PN"108"92;
"DQ<39>"
$PN"247"93;
"DQ<37>"
$PN"240"94;
"DQ<34>"
$PN"104"95;
"DQ<33>"
$PN"242"96;
"DQ<32>"
$PN"97"97;
"DQ<31>"
$PN"188"98;
"DQ<30>"
$PN"43"99;
"DQ<25>"
$PN"183"100;
"DQ<24>"
$PN"38"101;
"DQ<23>"
$PN"177"102;
"DQ<22>"
$PN"32"103;
"DQ<21>"
$PN"170"104;
"DQ<20>"
$PN"25"105;
"DQ<19>"
$PN"179"106;
"DQ<18>"
$PN"34"107;
"DQ<16>"
$PN"27"108;
"DQ<14>"
$PN"21"109;
"DQ<13>"
$PN"159"110;
"DQ<12>"
$PN"14"111;
"DQ<11>"
$PN"168"112;
"DQ<10>"
$PN"23"138;
"DQ<9>"
$PN"161"113;
"DQ<8>"
$PN"16"139;
"DQ<7>"
$PN"155"114;
"DQ<6>"
$PN"10"115;
"EVENT_N"
$PN"78"29;
"PAR"
$PN"222"37;
"RESET_N"
$PN"58"38;
"RFU<2>"
$PN"144"25;
"SCL"
$PN"141"31;
"SDA"
$PN"285"30;
"VREFCA"
$PN"146"22;
"CK1P"
$PN"218"49;
"BG<0>"
$PN"63"60;
"BG<1>"
$PN"207"61;
"BA<0>"
$PN"81"62;
"SA<0>"
$PN"139"19;
"VDDSPD"
$PN"284"19;
"SA<2>"
$PN"238"18;
"SA<1>"
$PN"140"18;
"DQ<1>"
$PN"150"116;
"DQ<0>"
$PN"5"117;
"ACT_N"
$PN"62"23;
"ALERT_N"
$PN"208"24;
"A2"
$PN"216"63;
"DQ<35>"
$PN"249"118;
"DQ<36>"
$PN"95"119;
"DQ<38>"
$PN"102"120;
"A10"
$PN"225"71;
"A11"
$PN"210"72;
"A14_WE_N"
$PN"228"73;
"A15_CAS_N"
$PN"86"75;
"A16_RAS_N"
$PN"82"76;
"CB<7>"
$PN"199"41;
"ODT<0>"
$PN"87"42;
"ODT<1>"
$PN"91"43;
"CKE<0>"
$PN"60"45;
"S0_N"
$PN"84"52;
"DQ<27>"
$PN"190"140;
"DQ<26>"
$PN"45"121;
"DQ<15>"
$PN"166"122;
"DQ<17>"
$PN"172"123;
"RFU<0>"
$PN"205"26;
"RFU<1>"
$PN"227"27;
"SAVE_N_NC"
$PN"230"28;
"DQ<57>"
$PN"275"124;
"DQ<58>"
$PN"137"125;
"DQ<54>"
$PN"124"126;
"DQ<53>"
$PN"262"127;
"DQ<52>"
$PN"117"128;
"DQ<51>"
$PN"271"129;
"DQ<50>"
$PN"126"130;
"DQ<49>"
$PN"264"131;
"DQ<48>"
$PN"119"132;
"DQ<47>"
$PN"258"133;
"DQ<2>"
$PN"12"134;
"DQ<3>"
$PN"157"135;
"DQ<4>"
$PN"3"136;
"DQ<5>"
$PN"148"137;
%"TAP"
"6","(125,3975)","2","mstr_standard","I135";
;
HDL_TAP"TRUE"
BODY_TYPE"PLUMBING"
CDS_LIB"mstr_standard";
"B \NAC \NWC"3;
"S \NAC"
BN"58"125;
%"TAP"
"6","(125,3925)","2","mstr_standard","I136";
;
HDL_TAP"TRUE"
BODY_TYPE"PLUMBING"
CDS_LIB"mstr_standard";
"B \NAC \NWC"3;
"S \NAC"
BN"57"124;
%"TAP"
"6","(125,4025)","2","mstr_standard","I137";
;
HDL_TAP"TRUE"
BODY_TYPE"PLUMBING"
CDS_LIB"mstr_standard";
"B \NAC \NWC"3;
"S \NAC"
BN"59"83;
%"TAP"
"6","(125,4125)","2","mstr_standard","I138";
;
HDL_TAP"TRUE"
BODY_TYPE"PLUMBING"
CDS_LIB"mstr_standard";
"B \NAC \NWC"3;
"S \NAC"
BN"61"81;
%"TAP"
"6","(125,4075)","2","mstr_standard","I139";
;
HDL_TAP"TRUE"
BODY_TYPE"PLUMBING"
CDS_LIB"mstr_standard";
"B \NAC \NWC"3;
"S \NAC"
BN"60"82;
%"TAP"
"6","(125,4175)","2","mstr_standard","I140";
;
HDL_TAP"TRUE"
BODY_TYPE"PLUMBING"
CDS_LIB"mstr_standard";
"B \NAC \NWC"3;
"S \NAC"
BN"62"80;
%"TAP"
"6","(125,4225)","2","mstr_standard","I141";
;
HDL_TAP"TRUE"
BODY_TYPE"PLUMBING"
CDS_LIB"mstr_standard";
"B \NAC \NWC"3;
"S \NAC"
BN"63"77;
%"GND"
"1","(2850,700)","2","mstr_symbols","I143";
;
HDL_POWER"GND"
ROOM"DDR4_GH_G"
BODY_TYPE"PLUMBING"
BOM_COST"MEM"
CDS_LIB"mstr_symbols"
SIZE"1B"
VOLTAGE"0.0V";
"A\NAC"15;
%"SCONN288_H44441003"
"3","(3550,2000)","0","mstr_sconn","I144";
;
CDS_SEC"3"
ROOM"DDR4_GH_G"
CDS_LOCATION"J9T1"
SEC"3"
SEC_TYPE"PIP"
CDS_LIB"mstr_sconn"
BOM_COST"MEM"
PACK_TYPE"PIP"
MATERIAL"SCONN"
PART_NUMBER"H44441-003"
LOCATION"J9T1";
"VSS<46>"
$PN"147"16;
"VSS<45>"
$PN"149"16;
"VSS<87>"
$PN"15"15;
"VSS<86>"
$PN"17"15;
"VSS<85>"
$PN"20"15;
"VSS<84>"
$PN"22"15;
"VSS<83>"
$PN"24"15;
"VSS<82>"
$PN"26"15;
"VSS<81>"
$PN"28"15;
"VSS<80>"
$PN"31"15;
"VSS<79>"
$PN"33"15;
"VSS<78>"
$PN"35"15;
"VSS<77>"
$PN"37"15;
"VSS<76>"
$PN"39"15;
"VSS<75>"
$PN"42"15;
"VSS<74>"
$PN"44"15;
"VSS<73>"
$PN"46"15;
"VSS<72>"
$PN"48"15;
"VSS<71>"
$PN"50"15;
"VSS<70>"
$PN"53"15;
"VSS<69>"
$PN"55"15;
"VSS<68>"
$PN"57"15;
"VSS<67>"
$PN"94"15;
"VSS<66>"
$PN"96"15;
"VSS<65>"
$PN"98"15;
"VSS<64>"
$PN"101"15;
"VSS<63>"
$PN"103"15;
"VSS<62>"
$PN"105"15;
"VSS<61>"
$PN"107"15;
"VSS<60>"
$PN"109"15;
"VSS<59>"
$PN"112"15;
"VSS<58>"
$PN"114"15;
"VSS<57>"
$PN"116"15;
"VSS<56>"
$PN"118"15;
"VSS<55>"
$PN"120"15;
"VSS<54>"
$PN"123"15;
"VSS<53>"
$PN"125"15;
"VSS<52>"
$PN"127"15;
"VSS<51>"
$PN"129"15;
"VSS<50>"
$PN"131"15;
"VSS<49>"
$PN"134"15;
"VSS<48>"
$PN"136"15;
"VSS<47>"
$PN"138"15;
"VSS<44>"
$PN"151"16;
"VSS<43>"
$PN"154"16;
"VSS<42>"
$PN"156"16;
"VSS<41>"
$PN"158"16;
"VSS<40>"
$PN"160"16;
"VSS<39>"
$PN"162"16;
"VSS<38>"
$PN"165"16;
"VSS<37>"
$PN"167"16;
"VSS<36>"
$PN"169"16;
"VSS<35>"
$PN"171"16;
"VSS<34>"
$PN"173"16;
"VSS<33>"
$PN"176"16;
"VSS<32>"
$PN"178"16;
"VSS<31>"
$PN"180"16;
"VSS<30>"
$PN"182"16;
"VSS<29>"
$PN"184"16;
"VSS<28>"
$PN"187"16;
"VSS<27>"
$PN"189"16;
"VSS<26>"
$PN"191"16;
"VSS<25>"
$PN"193"16;
"VSS<24>"
$PN"195"16;
"VSS<23>"
$PN"198"16;
"VSS<22>"
$PN"200"16;
"VSS<21>"
$PN"202"16;
"VSS<20>"
$PN"239"16;
"VSS<19>"
$PN"241"16;
"VSS<18>"
$PN"243"16;
"VSS<17>"
$PN"246"16;
"VSS<16>"
$PN"248"16;
"VSS<15>"
$PN"250"16;
"VSS<14>"
$PN"252"16;
"VSS<13>"
$PN"254"16;
"VSS<12>"
$PN"257"16;
"VSS<11>"
$PN"259"16;
"VSS<10>"
$PN"261"16;
"VSS<9>"
$PN"263"16;
"VSS<8>"
$PN"265"16;
"VSS<7>"
$PN"268"16;
"VSS<6>"
$PN"270"16;
"VSS<5>"
$PN"272"16;
"VSS<4>"
$PN"274"16;
"VSS<3>"
$PN"276"16;
"VSS<2>"
$PN"279"16;
"VSS<1>"
$PN"281"16;
"VSS<0>"
$PN"283"16;
"VSS<88>"
$PN"13"15;
"VSS<89>"
$PN"11"15;
"VSS<90>"
$PN"9"15;
"VSS<91>"
$PN"6"15;
"VSS<92>"
$PN"4"15;
"VSS<93>"
$PN"2"15;
%"TAP"
"6","(2450,3250)","2","mstr_standard","I148";
;
HDL_TAP"TRUE"
BODY_TYPE"PLUMBING"
CDS_LIB"mstr_standard";
"B \NAC \NWC"2;
"S \NAC"
BN"1"142;
%"TAP"
"6","(2450,3150)","2","mstr_standard","I149";
;
HDL_TAP"TRUE"
BODY_TYPE"PLUMBING"
CDS_LIB"mstr_standard";
"B \NAC \NWC"2;
"S \NAC"
BN"0"141;
%"TAP"
"6","(2450,3350)","2","mstr_standard","I150";
;
HDL_TAP"TRUE"
BODY_TYPE"PLUMBING"
CDS_LIB"mstr_standard";
"B \NAC \NWC"2;
"S \NAC"
BN"2"143;
%"TAP"
"6","(2650,3100)","2","mstr_standard","I151";
;
HDL_TAP"TRUE"
BODY_TYPE"PLUMBING"
CDS_LIB"mstr_standard";
"B \NAC \NWC"1;
"S \NAC"
BN"0"151;
%"TAP"
"6","(2650,3200)","2","mstr_standard","I152";
;
HDL_TAP"TRUE"
BODY_TYPE"PLUMBING"
CDS_LIB"mstr_standard";
"B \NAC \NWC"1;
"S \NAC"
BN"1"152;
%"TAP"
"6","(2650,3300)","2","mstr_standard","I153";
;
HDL_TAP"TRUE"
BODY_TYPE"PLUMBING"
CDS_LIB"mstr_standard";
"B \NAC \NWC"1;
"S \NAC"
BN"2"153;
%"TAP"
"6","(2450,3450)","2","mstr_standard","I154";
;
HDL_TAP"TRUE"
BODY_TYPE"PLUMBING"
CDS_LIB"mstr_standard";
"B \NAC \NWC"2;
"S \NAC"
BN"3"144;
%"TAP"
"6","(2450,3550)","2","mstr_standard","I155";
;
HDL_TAP"TRUE"
BODY_TYPE"PLUMBING"
CDS_LIB"mstr_standard";
"B \NAC \NWC"2;
"S \NAC"
BN"4"145;
%"TAP"
"6","(2450,3750)","2","mstr_standard","I156";
;
HDL_TAP"TRUE"
BODY_TYPE"PLUMBING"
CDS_LIB"mstr_standard";
"B \NAC \NWC"2;
"S \NAC"
BN"6"147;
%"TAP"
"6","(2450,3650)","2","mstr_standard","I157";
;
HDL_TAP"TRUE"
BODY_TYPE"PLUMBING"
CDS_LIB"mstr_standard";
"B \NAC \NWC"2;
"S \NAC"
BN"5"146;
%"TAP"
"6","(2450,3850)","2","mstr_standard","I158";
;
HDL_TAP"TRUE"
BODY_TYPE"PLUMBING"
CDS_LIB"mstr_standard";
"B \NAC \NWC"2;
"S \NAC"
BN"7"148;
%"TAP"
"6","(2650,3500)","2","mstr_standard","I159";
;
HDL_TAP"TRUE"
BODY_TYPE"PLUMBING"
CDS_LIB"mstr_standard";
"B \NAC \NWC"1;
"S \NAC"
BN"4"155;
%"TAP"
"6","(2650,3400)","2","mstr_standard","I160";
;
HDL_TAP"TRUE"
BODY_TYPE"PLUMBING"
CDS_LIB"mstr_standard";
"B \NAC \NWC"1;
"S \NAC"
BN"3"154;
%"TAP"
"6","(2650,3600)","2","mstr_standard","I161";
;
HDL_TAP"TRUE"
BODY_TYPE"PLUMBING"
CDS_LIB"mstr_standard";
"B \NAC \NWC"1;
"S \NAC"
BN"5"156;
%"TAP"
"6","(2650,3800)","2","mstr_standard","I162";
;
HDL_TAP"TRUE"
BODY_TYPE"PLUMBING"
CDS_LIB"mstr_standard";
"B \NAC \NWC"1;
"S \NAC"
BN"7"158;
%"TAP"
"6","(2650,3700)","2","mstr_standard","I163";
;
HDL_TAP"TRUE"
BODY_TYPE"PLUMBING"
CDS_LIB"mstr_standard";
"B \NAC \NWC"1;
"S \NAC"
BN"6"157;
%"GND"
"1","(4250,700)","2","mstr_symbols","I164";
;
HDL_POWER"GND"
ROOM"DDR4_GH_G"
BODY_TYPE"PLUMBING"
BOM_COST"MEM"
CDS_LIB"mstr_symbols"
SIZE"1B"
VOLTAGE"0.0V";
"A\NAC"16;
%"TAP"
"6","(2450,3950)","2","mstr_standard","I165";
;
HDL_TAP"TRUE"
BODY_TYPE"PLUMBING"
CDS_LIB"mstr_standard";
"B \NAC \NWC"2;
"S \NAC"
BN"8"149;
%"TAP"
"6","(2450,4150)","2","mstr_standard","I166";
;
HDL_TAP"TRUE"
BODY_TYPE"PLUMBING"
CDS_LIB"mstr_standard";
"B \NAC \NWC"2;
"S \NAC"
BN"10"161;
%"TAP"
"6","(2450,4050)","2","mstr_standard","I167";
;
HDL_TAP"TRUE"
BODY_TYPE"PLUMBING"
CDS_LIB"mstr_standard";
"B \NAC \NWC"2;
"S \NAC"
BN"9"150;
%"TAP"
"6","(2450,4250)","2","mstr_standard","I168";
;
HDL_TAP"TRUE"
BODY_TYPE"PLUMBING"
CDS_LIB"mstr_standard";
"B \NAC \NWC"2;
"S \NAC"
BN"11"162;
%"TAP"
"6","(2450,4350)","2","mstr_standard","I169";
;
HDL_TAP"TRUE"
BODY_TYPE"PLUMBING"
CDS_LIB"mstr_standard";
"B \NAC \NWC"2;
"S \NAC"
BN"12"163;
%"TAP"
"6","(2650,4000)","2","mstr_standard","I170";
;
HDL_TAP"TRUE"
BODY_TYPE"PLUMBING"
CDS_LIB"mstr_standard";
"B \NAC \NWC"1;
"S \NAC"
BN"9"160;
%"TAP"
"6","(2650,4100)","2","mstr_standard","I171";
;
HDL_TAP"TRUE"
BODY_TYPE"PLUMBING"
CDS_LIB"mstr_standard";
"B \NAC \NWC"1;
"S \NAC"
BN"10"169;
%"TAP"
"6","(2650,3900)","2","mstr_standard","I172";
;
HDL_TAP"TRUE"
BODY_TYPE"PLUMBING"
CDS_LIB"mstr_standard";
"B \NAC \NWC"1;
"S \NAC"
BN"8"159;
%"TAP"
"6","(2650,4200)","2","mstr_standard","I173";
;
HDL_TAP"TRUE"
BODY_TYPE"PLUMBING"
CDS_LIB"mstr_standard";
"B \NAC \NWC"1;
"S \NAC"
BN"11"170;
%"TAP"
"6","(2650,4400)","2","mstr_standard","I174";
;
HDL_TAP"TRUE"
BODY_TYPE"PLUMBING"
CDS_LIB"mstr_standard";
"B \NAC \NWC"1;
"S \NAC"
BN"13"172;
%"TAP"
"6","(2650,4300)","2","mstr_standard","I175";
;
HDL_TAP"TRUE"
BODY_TYPE"PLUMBING"
CDS_LIB"mstr_standard";
"B \NAC \NWC"1;
"S \NAC"
BN"12"171;
%"TAP"
"6","(2450,4450)","2","mstr_standard","I176";
;
HDL_TAP"TRUE"
BODY_TYPE"PLUMBING"
CDS_LIB"mstr_standard";
"B \NAC \NWC"2;
"S \NAC"
BN"13"164;
%"TAP"
"6","(2450,4550)","2","mstr_standard","I177";
;
HDL_TAP"TRUE"
BODY_TYPE"PLUMBING"
CDS_LIB"mstr_standard";
"B \NAC \NWC"2;
"S \NAC"
BN"14"165;
%"TAP"
"6","(2450,4650)","2","mstr_standard","I178";
;
HDL_TAP"TRUE"
BODY_TYPE"PLUMBING"
CDS_LIB"mstr_standard";
"B \NAC \NWC"2;
"S \NAC"
BN"15"166;
%"TAP"
"6","(2450,4750)","2","mstr_standard","I179";
;
HDL_TAP"TRUE"
BODY_TYPE"PLUMBING"
CDS_LIB"mstr_standard";
"B \NAC \NWC"2;
"S \NAC"
BN"16"167;
%"TAP"
"6","(2450,4850)","2","mstr_standard","I180";
;
HDL_TAP"TRUE"
BODY_TYPE"PLUMBING"
CDS_LIB"mstr_standard";
"B \NAC \NWC"2;
"S \NAC"
BN"17"168;
%"TAP"
"6","(2650,4600)","2","mstr_standard","I181";
;
HDL_TAP"TRUE"
BODY_TYPE"PLUMBING"
CDS_LIB"mstr_standard";
"B \NAC \NWC"1;
"S \NAC"
BN"15"174;
%"TAP"
"6","(2650,4500)","2","mstr_standard","I182";
;
HDL_TAP"TRUE"
BODY_TYPE"PLUMBING"
CDS_LIB"mstr_standard";
"B \NAC \NWC"1;
"S \NAC"
BN"14"173;
%"TAP"
"6","(2650,4800)","2","mstr_standard","I183";
;
HDL_TAP"TRUE"
BODY_TYPE"PLUMBING"
CDS_LIB"mstr_standard";
"B \NAC \NWC"1;
"S \NAC"
BN"17"176;
%"TAP"
"6","(2650,4700)","2","mstr_standard","I184";
;
HDL_TAP"TRUE"
BODY_TYPE"PLUMBING"
CDS_LIB"mstr_standard";
"B \NAC \NWC"1;
"S \NAC"
BN"16"175;
%"P12V_NVDIMM_GHJ"
"1","(2150,2725)","0","mstr_symbols","I187";
;
HDL_POWER"P12V_NVDIMM_GHJ"
BODY_TYPE"PLUMBING"
CDS_LIB"mstr_symbols"
VOLTAGE"12.0";
"G\NAC"17;
%"CAP_A"
"1","(-2675,875)","2","dev_discrete","I2";
;
ROOM"DDR4_GH_G"
$SEC"1"
CDS_SEC"1"
CDS_LIB"dev_discrete"
BOM_COST"MEM"
CDS_LOCATION"C9T7"
MATERIAL"X7R"
VOLTAGE"25V"
PACK_TYPE"0402V"
TOLERANCE"10%"
VALUE"0.01UF"
PART_NUMBER"A36096-045"
LOCATION"C9T7";
"B"
$PN"2"13;
"A"
$PN"1"22;
%"TAP"
"6","(-1375,1875)","0","mstr_standard","I21";
;
HDL_TAP"TRUE"
BODY_TYPE"PLUMBING"
CDS_LIB"mstr_standard";
"B \NAC \NWC"12;
"S \NAC"
BN"1"35;
%"TAP"
"6","(-1375,1925)","0","mstr_standard","I22";
;
HDL_TAP"TRUE"
BODY_TYPE"PLUMBING"
CDS_LIB"mstr_standard";
"B \NAC \NWC"12;
"S \NAC"
BN"2"34;
%"TAP"
"6","(-1375,1975)","0","mstr_standard","I23";
;
HDL_TAP"TRUE"
BODY_TYPE"PLUMBING"
CDS_LIB"mstr_standard";
"B \NAC \NWC"12;
"S \NAC"
BN"3"33;
%"TAP"
"6","(-1375,2075)","0","mstr_standard","I24";
;
HDL_TAP"TRUE"
BODY_TYPE"PLUMBING"
CDS_LIB"mstr_standard";
"B \NAC \NWC"12;
"S \NAC"
BN"5"40;
%"TAP"
"6","(-1375,2025)","0","mstr_standard","I25";
;
HDL_TAP"TRUE"
BODY_TYPE"PLUMBING"
CDS_LIB"mstr_standard";
"B \NAC \NWC"12;
"S \NAC"
BN"4"32;
%"TAP"
"6","(-1375,2175)","0","mstr_standard","I26";
;
HDL_TAP"TRUE"
BODY_TYPE"PLUMBING"
CDS_LIB"mstr_standard";
"B \NAC \NWC"12;
"S \NAC"
BN"7"41;
%"TAP"
"6","(-1375,2125)","0","mstr_standard","I27";
;
HDL_TAP"TRUE"
BODY_TYPE"PLUMBING"
CDS_LIB"mstr_standard";
"B \NAC \NWC"12;
"S \NAC"
BN"6"39;
%"TAP"
"6","(-1375,2325)","0","mstr_standard","I28";
;
HDL_TAP"TRUE"
BODY_TYPE"PLUMBING"
CDS_LIB"mstr_standard";
"B \NAC \NWC"11;
"S \NAC"
BN"3"43;
%"TAP"
"6","(-1375,2275)","0","mstr_standard","I29";
;
HDL_TAP"TRUE"
BODY_TYPE"PLUMBING"
CDS_LIB"mstr_standard";
"B \NAC \NWC"11;
"S \NAC"
BN"2"42;
%"GND"
"1","(-3325,1225)","2","mstr_symbols","I3";
;
HDL_POWER"GND"
ROOM"DDR4_GH_G"
BODY_TYPE"PLUMBING"
BOM_COST"MEM"
CDS_LIB"mstr_symbols"
SIZE"1B"
VOLTAGE"0.0V";
"A\NAC"18;
%"TAP"
"6","(-1375,2425)","0","mstr_standard","I30";
;
HDL_TAP"TRUE"
BODY_TYPE"PLUMBING"
CDS_LIB"mstr_standard";
"B \NAC \NWC"10;
"S \NAC"
BN"2"45;
%"TAP"
"6","(-1375,2475)","0","mstr_standard","I31";
;
HDL_TAP"TRUE"
BODY_TYPE"PLUMBING"
CDS_LIB"mstr_standard";
"B \NAC \NWC"10;
"S \NAC"
BN"3"44;
%"TAP"
"6","(-1375,2575)","0","mstr_standard","I32";
;
HDL_TAP"TRUE"
BODY_TYPE"PLUMBING"
CDS_LIB"mstr_standard";
"B \NAC \NWC"8;
"S \NAC"
BN"4"52;
%"TAP"
"6","(-1375,2675)","0","mstr_standard","I33";
;
HDL_TAP"TRUE"
BODY_TYPE"PLUMBING"
CDS_LIB"mstr_standard";
"B \NAC \NWC"8;
"S \NAC"
BN"6"50;
%"TAP"
"6","(-1375,2625)","0","mstr_standard","I34";
;
HDL_TAP"TRUE"
BODY_TYPE"PLUMBING"
CDS_LIB"mstr_standard";
"B \NAC \NWC"8;
"S \NAC"
BN"5"51;
%"TAP"
"6","(-1375,2725)","0","mstr_standard","I35";
;
HDL_TAP"TRUE"
BODY_TYPE"PLUMBING"
CDS_LIB"mstr_standard";
"B \NAC \NWC"8;
"S \NAC"
BN"7"48;
%"TAP"
"6","(-1575,2975)","0","mstr_standard","I40";
;
HDL_TAP"TRUE"
BODY_TYPE"PLUMBING"
CDS_LIB"mstr_standard";
"B \NAC \NWC"7;
"S \NAC"
BN"3"46;
%"TAP"
"6","(-1575,2875)","0","mstr_standard","I41";
;
HDL_TAP"TRUE"
BODY_TYPE"PLUMBING"
CDS_LIB"mstr_standard";
"B \NAC \NWC"7;
"S \NAC"
BN"2"53;
%"TAP"
"6","(-1375,2925)","0","mstr_standard","I42";
;
HDL_TAP"TRUE"
BODY_TYPE"PLUMBING"
CDS_LIB"mstr_standard";
"B \NAC \NWC"9;
"S \NAC"
BN"2"47;
%"TAP"
"6","(-1375,3025)","0","mstr_standard","I43";
;
HDL_TAP"TRUE"
BODY_TYPE"PLUMBING"
CDS_LIB"mstr_standard";
"B \NAC \NWC"9;
"S \NAC"
BN"3"49;
%"TAP"
"6","(-1375,3125)","0","mstr_standard","I44";
;
HDL_TAP"TRUE"
BODY_TYPE"PLUMBING"
CDS_LIB"mstr_standard";
"B \NAC \NWC"6;
"S \NAC"
BN"0"60;
%"TAP"
"6","(-1375,3225)","0","mstr_standard","I45";
;
HDL_TAP"TRUE"
BODY_TYPE"PLUMBING"
CDS_LIB"mstr_standard";
"B \NAC \NWC"5;
"S \NAC"
BN"0"62;
%"TAP"
"6","(-1375,3175)","0","mstr_standard","I46";
;
HDL_TAP"TRUE"
BODY_TYPE"PLUMBING"
CDS_LIB"mstr_standard";
"B \NAC \NWC"6;
"S \NAC"
BN"1"61;
%"TAP"
"6","(-1375,3275)","0","mstr_standard","I47";
;
HDL_TAP"TRUE"
BODY_TYPE"PLUMBING"
CDS_LIB"mstr_standard";
"B \NAC \NWC"5;
"S \NAC"
BN"1"55;
%"TAP"
"6","(-1375,3375)","0","mstr_standard","I48";
;
HDL_TAP"TRUE"
BODY_TYPE"PLUMBING"
CDS_LIB"mstr_standard";
"B \NAC \NWC"4;
"S \NAC"
BN"0"56;
%"TAP"
"6","(-1375,3475)","0","mstr_standard","I49";
;
HDL_TAP"TRUE"
BODY_TYPE"PLUMBING"
CDS_LIB"mstr_standard";
"B \NAC \NWC"4;
"S \NAC"
BN"2"63;
%"PVPP_GHJ"
"1","(-3325,1575)","0","mstr_symbols","I5";
;
HDL_POWER"PVPP_GHJ"
ROOM"DDR4_GH_G"
BODY_TYPE"PLUMBING"
CDS_LIB"mstr_symbols"
BOM_COST"MEM"
VOLTAGE"2.5V";
"G\NAC"19;
%"TAP"
"6","(-1375,3425)","0","mstr_standard","I50";
;
HDL_TAP"TRUE"
BODY_TYPE"PLUMBING"
CDS_LIB"mstr_standard";
"B \NAC \NWC"4;
"S \NAC"
BN"1"57;
%"TAP"
"6","(-1375,3575)","0","mstr_standard","I51";
;
HDL_TAP"TRUE"
BODY_TYPE"PLUMBING"
CDS_LIB"mstr_standard";
"B \NAC \NWC"4;
"S \NAC"
BN"4"59;
%"TAP"
"6","(-1375,3525)","0","mstr_standard","I52";
;
HDL_TAP"TRUE"
BODY_TYPE"PLUMBING"
CDS_LIB"mstr_standard";
"B \NAC \NWC"4;
"S \NAC"
BN"3"58;
%"TAP"
"6","(-1375,3625)","0","mstr_standard","I53";
;
HDL_TAP"TRUE"
BODY_TYPE"PLUMBING"
CDS_LIB"mstr_standard";
"B \NAC \NWC"4;
"S \NAC"
BN"5"66;
%"TAP"
"6","(-1375,3675)","0","mstr_standard","I54";
;
HDL_TAP"TRUE"
BODY_TYPE"PLUMBING"
CDS_LIB"mstr_standard";
"B \NAC \NWC"4;
"S \NAC"
BN"6"67;
%"TAP"
"6","(-1375,3725)","0","mstr_standard","I55";
;
HDL_TAP"TRUE"
BODY_TYPE"PLUMBING"
CDS_LIB"mstr_standard";
"B \NAC \NWC"4;
"S \NAC"
BN"7"68;
%"TAP"
"6","(-1375,3825)","0","mstr_standard","I56";
;
HDL_TAP"TRUE"
BODY_TYPE"PLUMBING"
CDS_LIB"mstr_standard";
"B \NAC \NWC"4;
"S \NAC"
BN"9"70;
%"TAP"
"6","(-1375,3775)","0","mstr_standard","I57";
;
HDL_TAP"TRUE"
BODY_TYPE"PLUMBING"
CDS_LIB"mstr_standard";
"B \NAC \NWC"4;
"S \NAC"
BN"8"69;
%"TAP"
"6","(-1375,3875)","0","mstr_standard","I58";
;
HDL_TAP"TRUE"
BODY_TYPE"PLUMBING"
CDS_LIB"mstr_standard";
"B \NAC \NWC"4;
"S \NAC"
BN"10"71;
%"TAP"
"6","(125,1075)","2","mstr_standard","I59";
;
HDL_TAP"TRUE"
BODY_TYPE"PLUMBING"
CDS_LIB"mstr_standard";
"B \NAC \NWC"3;
"S \NAC"
BN"0"117;
%"TAP"
"6","(125,1125)","2","mstr_standard","I60";
;
HDL_TAP"TRUE"
BODY_TYPE"PLUMBING"
CDS_LIB"mstr_standard";
"B \NAC \NWC"3;
"S \NAC"
BN"1"116;
%"TAP"
"6","(125,1175)","2","mstr_standard","I61";
;
HDL_TAP"TRUE"
BODY_TYPE"PLUMBING"
CDS_LIB"mstr_standard";
"B \NAC \NWC"3;
"S \NAC"
BN"2"134;
%"TAP"
"6","(125,1325)","2","mstr_standard","I62";
;
HDL_TAP"TRUE"
BODY_TYPE"PLUMBING"
CDS_LIB"mstr_standard";
"B \NAC \NWC"3;
"S \NAC"
BN"5"137;
%"TAP"
"6","(125,1275)","2","mstr_standard","I63";
;
HDL_TAP"TRUE"
BODY_TYPE"PLUMBING"
CDS_LIB"mstr_standard";
"B \NAC \NWC"3;
"S \NAC"
BN"4"136;
%"TAP"
"6","(125,1225)","2","mstr_standard","I64";
;
HDL_TAP"TRUE"
BODY_TYPE"PLUMBING"
CDS_LIB"mstr_standard";
"B \NAC \NWC"3;
"S \NAC"
BN"3"135;
%"TAP"
"6","(125,1375)","2","mstr_standard","I65";
;
HDL_TAP"TRUE"
BODY_TYPE"PLUMBING"
CDS_LIB"mstr_standard";
"B \NAC \NWC"3;
"S \NAC"
BN"6"115;
%"TAP"
"6","(125,1425)","2","mstr_standard","I66";
;
HDL_TAP"TRUE"
BODY_TYPE"PLUMBING"
CDS_LIB"mstr_standard";
"B \NAC \NWC"3;
"S \NAC"
BN"7"114;
%"TAP"
"6","(125,1475)","2","mstr_standard","I67";
;
HDL_TAP"TRUE"
BODY_TYPE"PLUMBING"
CDS_LIB"mstr_standard";
"B \NAC \NWC"3;
"S \NAC"
BN"8"139;
%"TAP"
"6","(125,1525)","2","mstr_standard","I68";
;
HDL_TAP"TRUE"
BODY_TYPE"PLUMBING"
CDS_LIB"mstr_standard";
"B \NAC \NWC"3;
"S \NAC"
BN"9"113;
%"TAP"
"6","(125,1575)","2","mstr_standard","I69";
;
HDL_TAP"TRUE"
BODY_TYPE"PLUMBING"
CDS_LIB"mstr_standard";
"B \NAC \NWC"3;
"S \NAC"
BN"10"138;
%"TAP"
"6","(125,1725)","2","mstr_standard","I70";
;
HDL_TAP"TRUE"
BODY_TYPE"PLUMBING"
CDS_LIB"mstr_standard";
"B \NAC \NWC"3;
"S \NAC"
BN"13"110;
%"TAP"
"6","(125,1625)","2","mstr_standard","I71";
;
HDL_TAP"TRUE"
BODY_TYPE"PLUMBING"
CDS_LIB"mstr_standard";
"B \NAC \NWC"3;
"S \NAC"
BN"11"112;
%"TAP"
"6","(125,1675)","2","mstr_standard","I72";
;
HDL_TAP"TRUE"
BODY_TYPE"PLUMBING"
CDS_LIB"mstr_standard";
"B \NAC \NWC"3;
"S \NAC"
BN"12"111;
%"TAP"
"6","(125,1775)","2","mstr_standard","I73";
;
HDL_TAP"TRUE"
BODY_TYPE"PLUMBING"
CDS_LIB"mstr_standard";
"B \NAC \NWC"3;
"S \NAC"
BN"14"109;
%"TAP"
"6","(125,1825)","2","mstr_standard","I74";
;
HDL_TAP"TRUE"
BODY_TYPE"PLUMBING"
CDS_LIB"mstr_standard";
"B \NAC \NWC"3;
"S \NAC"
BN"15"122;
%"SCONN288_H44441003"
"4","(1450,1750)","0","mstr_sconn","I75";
;
CDS_SEC"4"
ROOM"DDR4_GH_G"
CDS_LOCATION"J9T1"
SEC"4"
SEC_TYPE"PIP"
CDS_LIB"mstr_sconn"
BOM_COST"MEM"
PACK_TYPE"PIP"
MATERIAL"SCONN"
PART_NUMBER"H44441-003"
LOCATION"J9T1";
"VDD<0>"
$PN"236"20;
"VDD<6>"
$PN"220"20;
"VDD<10>"
$PN"209"20;
"VDD<13>"
$PN"92"20;
"VDD<16>"
$PN"85"20;
"VDD<19>"
$PN"76"20;
"VDD<23>"
$PN"64"20;
"VDD<25>"
$PN"59"20;
"VTT<0>"
$PN"221"21;
"12V<1>"
$PN"1"17;
"12V<0>"
$PN"145"17;
"VDD<24>"
$PN"61"20;
"VDD<22>"
$PN"67"20;
"VDD<21>"
$PN"70"20;
"VDD<20>"
$PN"73"20;
"VDD<18>"
$PN"80"20;
"VDD<17>"
$PN"83"20;
"VDD<15>"
$PN"88"20;
"VDD<14>"
$PN"90"20;
"VDD<12>"
$PN"204"20;
"VDD<11>"
$PN"206"20;
"VDD<9>"
$PN"212"20;
"VDD<8>"
$PN"215"20;
"VDD<7>"
$PN"217"20;
"VDD<5>"
$PN"223"20;
"VDD<4>"
$PN"226"20;
"VDD<3>"
$PN"229"20;
"VDD<2>"
$PN"231"20;
"VDD<1>"
$PN"233"20;
"VPP<4>"
$PN"142"14;
"VPP<3>"
$PN"143"14;
"VPP<2>"
$PN"288"14;
"VPP<1>"
$PN"286"14;
"VPP<0>"
$PN"287"14;
"VTT<1>"
$PN"77"21;
%"TAP"
"6","(125,1925)","2","mstr_standard","I76";
;
HDL_TAP"TRUE"
BODY_TYPE"PLUMBING"
CDS_LIB"mstr_standard";
"B \NAC \NWC"3;
"S \NAC"
BN"17"123;
%"TAP"
"6","(125,1875)","2","mstr_standard","I77";
;
HDL_TAP"TRUE"
BODY_TYPE"PLUMBING"
CDS_LIB"mstr_standard";
"B \NAC \NWC"3;
"S \NAC"
BN"16"108;
%"TAP"
"6","(125,1975)","2","mstr_standard","I78";
;
HDL_TAP"TRUE"
BODY_TYPE"PLUMBING"
CDS_LIB"mstr_standard";
"B \NAC \NWC"3;
"S \NAC"
BN"18"107;
%"TAP"
"6","(125,2025)","2","mstr_standard","I79";
;
HDL_TAP"TRUE"
BODY_TYPE"PLUMBING"
CDS_LIB"mstr_standard";
"B \NAC \NWC"3;
"S \NAC"
BN"19"106;
%"TAP"
"6","(125,2075)","2","mstr_standard","I80";
;
HDL_TAP"TRUE"
BODY_TYPE"PLUMBING"
CDS_LIB"mstr_standard";
"B \NAC \NWC"3;
"S \NAC"
BN"20"105;
%"TAP"
"6","(125,2225)","2","mstr_standard","I81";
;
HDL_TAP"TRUE"
BODY_TYPE"PLUMBING"
CDS_LIB"mstr_standard";
"B \NAC \NWC"3;
"S \NAC"
BN"23"102;
%"TAP"
"6","(125,2175)","2","mstr_standard","I82";
;
HDL_TAP"TRUE"
BODY_TYPE"PLUMBING"
CDS_LIB"mstr_standard";
"B \NAC \NWC"3;
"S \NAC"
BN"22"103;
%"TAP"
"6","(125,2125)","2","mstr_standard","I83";
;
HDL_TAP"TRUE"
BODY_TYPE"PLUMBING"
CDS_LIB"mstr_standard";
"B \NAC \NWC"3;
"S \NAC"
BN"21"104;
%"TAP"
"6","(125,2325)","2","mstr_standard","I84";
;
HDL_TAP"TRUE"
BODY_TYPE"PLUMBING"
CDS_LIB"mstr_standard";
"B \NAC \NWC"3;
"S \NAC"
BN"25"100;
%"TAP"
"6","(125,2275)","2","mstr_standard","I85";
;
HDL_TAP"TRUE"
BODY_TYPE"PLUMBING"
CDS_LIB"mstr_standard";
"B \NAC \NWC"3;
"S \NAC"
BN"24"101;
%"TAP"
"6","(125,2475)","2","mstr_standard","I86";
;
HDL_TAP"TRUE"
BODY_TYPE"PLUMBING"
CDS_LIB"mstr_standard";
"B \NAC \NWC"3;
"S \NAC"
BN"28"79;
%"TAP"
"6","(125,2425)","2","mstr_standard","I87";
;
HDL_TAP"TRUE"
BODY_TYPE"PLUMBING"
CDS_LIB"mstr_standard";
"B \NAC \NWC"3;
"S \NAC"
BN"27"140;
%"TAP"
"6","(125,2375)","2","mstr_standard","I88";
;
HDL_TAP"TRUE"
BODY_TYPE"PLUMBING"
CDS_LIB"mstr_standard";
"B \NAC \NWC"3;
"S \NAC"
BN"26"121;
%"TAP"
"6","(125,2525)","2","mstr_standard","I89";
;
HDL_TAP"TRUE"
BODY_TYPE"PLUMBING"
CDS_LIB"mstr_standard";
"B \NAC \NWC"3;
"S \NAC"
BN"29"78;
%"TAP"
"6","(125,2575)","2","mstr_standard","I90";
;
HDL_TAP"TRUE"
BODY_TYPE"PLUMBING"
CDS_LIB"mstr_standard";
"B \NAC \NWC"3;
"S \NAC"
BN"30"99;
%"TAP"
"6","(125,2675)","2","mstr_standard","I91";
;
HDL_TAP"TRUE"
BODY_TYPE"PLUMBING"
CDS_LIB"mstr_standard";
"B \NAC \NWC"3;
"S \NAC"
BN"32"97;
%"TAP"
"6","(125,2725)","2","mstr_standard","I92";
;
HDL_TAP"TRUE"
BODY_TYPE"PLUMBING"
CDS_LIB"mstr_standard";
"B \NAC \NWC"3;
"S \NAC"
BN"33"96;
%"TAP"
"6","(125,2625)","2","mstr_standard","I93";
;
HDL_TAP"TRUE"
BODY_TYPE"PLUMBING"
CDS_LIB"mstr_standard";
"B \NAC \NWC"3;
"S \NAC"
BN"31"98;
%"TAP"
"6","(125,2825)","2","mstr_standard","I94";
;
HDL_TAP"TRUE"
BODY_TYPE"PLUMBING"
CDS_LIB"mstr_standard";
"B \NAC \NWC"3;
"S \NAC"
BN"35"118;
%"TAP"
"6","(125,2775)","2","mstr_standard","I95";
;
HDL_TAP"TRUE"
BODY_TYPE"PLUMBING"
CDS_LIB"mstr_standard";
"B \NAC \NWC"3;
"S \NAC"
BN"34"95;
%"PVDDQ_GHJ"
"1","(400,2300)","0","mstr_symbols","I96";
;
HDL_POWER"PVDDQ_GHJ"
ROOM"DDR4_GH_G"
BODY_TYPE"PLUMBING"
CDS_LIB"mstr_symbols"
BOM_COST"MEM"
VOLTAGE"1.2V";
"G\NAC"20;
%"PVTT_GHJ"
"1","(600,2450)","0","mstr_symbols","I97";
;
HDL_POWER"PVTT_GHJ"
ROOM"DDR4_GH_G"
BODY_TYPE"PLUMBING"
CDS_LIB"mstr_symbols"
BOM_COST"MEM"
VOLTAGE"0.6V";
"G\NAC"21;
%"TAP"
"6","(125,2875)","2","mstr_standard","I98";
;
HDL_TAP"TRUE"
BODY_TYPE"PLUMBING"
CDS_LIB"mstr_standard";
"B \NAC \NWC"3;
"S \NAC"
BN"36"119;
%"TAP"
"6","(125,2975)","2","mstr_standard","I99";
;
HDL_TAP"TRUE"
BODY_TYPE"PLUMBING"
CDS_LIB"mstr_standard";
"B \NAC \NWC"3;
"S \NAC"
BN"38"120;
END.
